# T6G (Grand Teton) — schematic netlist excerpt (pin names and nets, part order shuffled) for the footprints in the layout excerpt that follows; sources: Cadence DE-HDL packaged netlist, KiCad conversion of 04192023_DAF0TMB3IC0_F0TG_MB_C_brd_V02_OCP.brd

R1456  Q_RES  1K 1% EMPTY  pkg 0201LF  page 331 : A = P1V8_CPU1_RT_1D ; B = JTAG_TDO_RT_CPU1_P1
C8005  Q_CAP  0.1UF 25V 10% X7R  pkg 0402  page 85 : A = PWRGD_P5V_AUX_R3 ; B = GND
R3197  Q_RES  0 5% CHIP  pkg 0402LF  page 55 : A = CLK_100M_CPU1_CLK03_R_DN ; B = CLK_100M_CPU1_CLK03_DN

(kicad_pcb
	(version 20260206)
	(generator "pcbnew")
	(generator_version "10.0")
	(general
		(thickness 1.6)
		(legacy_teardrops no)
	)
	(paper "A4")
	(title_block
		(title "04192023_DAF0TMB3IC0_F0TG_MB_C_brd_V02_OCP.brd")
		(comment 1 "Grand Teton / footprints 539-541 of 8354")
	)
	(layers
		(0 "F.Cu" signal "TOP")
		(4 "In1.Cu" signal "GND")
		(6 "In2.Cu" signal "IN1")
		(8 "In3.Cu" signal "GND1")
		(10 "In4.Cu" signal "IN2")
		(12 "In5.Cu" signal "GND2")
		(14 "In6.Cu" signal "IN3")
		(16 "In7.Cu" signal "GND3")
		(18 "In8.Cu" signal "VCC")
		(20 "In9.Cu" signal "VCC1")
		(22 "In10.Cu" signal "GND4")
		(24 "In11.Cu" signal "IN4")
		(26 "In12.Cu" signal "GND5")
		(28 "In13.Cu" signal "IN5")
		(30 "In14.Cu" signal "GND6")
		(32 "In15.Cu" signal "IN6")
		(34 "In16.Cu" signal "GND7")
		(2 "B.Cu" signal "BOTTOM")
		(9 "F.Adhes" user "F.Adhesive")
		(11 "B.Adhes" user "B.Adhesive")
		(13 "F.Paste" user "Package Geometry/Pastemask Top")
		(15 "B.Paste" user "Package Geometry/Pastemask Bottom")
		(5 "F.SilkS" user "Ref Des/Silkscreen Top")
		(7 "B.SilkS" user "Ref Des/Silkscreen Bottom")
		(1 "F.Mask" user "Board Geometry/Soldermask Top")
		(3 "B.Mask" user "Board Geometry/Soldermask Bottom")
		(17 "Dwgs.User" user "User.Drawings")
		(19 "Cmts.User" user "User.Comments")
		(21 "Eco1.User" user "User.Eco1")
		(23 "Eco2.User" user "User.Eco2")
		(25 "Edge.Cuts" user "Board Geometry/Outline")
		(27 "Margin" user)
		(31 "F.CrtYd" user "Package Geometry/Place Bound Top")
		(29 "B.CrtYd" user "Package Geometry/Place Bound Bottom")
		(35 "F.Fab" user "Ref Des/Assembly Top")
		(33 "B.Fab" user "Ref Des/Assembly Bottom")
	)
	(footprint ""
		(layer "F.Cu")
		(at 208.892394 -107.467146)
		(property "Reference" "C8005"
			(at 0 0 0)
			(layer "F.SilkS")
			(hide yes)
			(effects
				(font
					(size 1.27 1.27)
				)
			)
		)
		(property "Value" ""
			(at 0 0 0)
			(layer "F.Fab")
			(effects
				(font
					(size 1.27 1.27)
				)
			)
		)
		(duplicate_pad_numbers_are_jumpers no)
		(fp_line
			(start -0.7874 -0.4064)
			(end 0.7874 -0.4064)
			(stroke
				(width 0.1524)
				(type default)
			)
			(layer "F.SilkS")
		)
		(fp_line
			(start -0.7874 0.4064)
			(end -0.7874 -0.4064)
			(stroke
				(width 0.1524)
				(type default)
			)
			(layer "F.SilkS")
		)
		(fp_line
			(start 0.7874 -0.4064)
			(end 0.7874 0.4064)
			(stroke
				(width 0.1524)
				(type default)
			)
			(layer "F.SilkS")
		)
		(fp_line
			(start 0.7874 0.4064)
			(end -0.7874 0.4064)
			(stroke
				(width 0.1524)
				(type default)
			)
			(layer "F.SilkS")
		)
		(fp_line
			(start -0.67945 -0.305054)
			(end -0.12065 -0.305054)
			(stroke
				(width 0.1)
				(type default)
			)
			(layer "F.Fab")
		)
		(fp_line
			(start -0.67945 0.3048)
			(end -0.67945 -0.305054)
			(stroke
				(width 0.1)
				(type default)
			)
			(layer "F.Fab")
		)
		(fp_line
			(start -0.12065 -0.305054)
			(end -0.12065 -0.2794)
			(stroke
				(width 0.1)
				(type default)
			)
			(layer "F.Fab")
		)
		(fp_line
			(start -0.12065 -0.2794)
			(end 0.12065 -0.2794)
			(stroke
				(width 0.1)
				(type default)
			)
			(layer "F.Fab")
		)
		(fp_line
			(start -0.12065 0.2794)
			(end -0.12065 0.3048)
			(stroke
				(width 0.1)
				(type default)
			)
			(layer "F.Fab")
		)
		(fp_line
			(start -0.12065 0.3048)
			(end -0.67945 0.3048)
			(stroke
				(width 0.1)
				(type default)
			)
			(layer "F.Fab")
		)
		(fp_line
			(start 0.120396 0.2794)
			(end -0.12065 0.2794)
			(stroke
				(width 0.1)
				(type default)
			)
			(layer "F.Fab")
		)
		(fp_line
			(start 0.120396 0.3048)
			(end 0.120396 0.2794)
			(stroke
				(width 0.1)
				(type default)
			)
			(layer "F.Fab")
		)
		(fp_line
			(start 0.12065 -0.3048)
			(end 0.67945 -0.3048)
			(stroke
				(width 0.1)
				(type default)
			)
			(layer "F.Fab")
		)
		(fp_line
			(start 0.12065 -0.2794)
			(end 0.12065 -0.3048)
			(stroke
				(width 0.1)
				(type default)
			)
			(layer "F.Fab")
		)
		(fp_line
			(start 0.67945 -0.3048)
			(end 0.67945 0.3048)
			(stroke
				(width 0.1)
				(type default)
			)
			(layer "F.Fab")
		)
		(fp_line
			(start 0.67945 0.3048)
			(end 0.120396 0.3048)
			(stroke
				(width 0.1)
				(type default)
			)
			(layer "F.Fab")
		)
		(pad "1" smd circle
			(at -0.40005 0)
			(size 0 0)
			(layers "F.Cu" "F.Mask" "F.Paste")
			(net "PWRGD_P5V_AUX_R3")
		)
		(pad "2" smd circle
			(at 0.40005 0)
			(size 0 0)
			(layers "F.Cu" "F.Mask" "F.Paste")
			(net "GND")
		)
	)
	(footprint ""
		(layer "F.Cu")
		(at 96.0628 -418.0332 180)
		(property "Reference" "R1456"
			(at 0 0 180)
			(layer "F.SilkS")
			(hide yes)
			(effects
				(font
					(size 1.27 1.27)
				)
			)
		)
		(property "Value" ""
			(at 0 0 180)
			(layer "F.Fab")
			(effects
				(font
					(size 1.27 1.27)
				)
			)
		)
		(duplicate_pad_numbers_are_jumpers no)
		(fp_line
			(start 0.32512 0.175006)
			(end -0.32512 0.175006)
			(stroke
				(width 0.1)
				(type default)
			)
			(layer "F.Fab")
		)
		(fp_line
			(start 0.32512 -0.175006)
			(end 0.32512 0.175006)
			(stroke
				(width 0.1)
				(type default)
			)
			(layer "F.Fab")
		)
		(fp_line
			(start -0.32512 0.175006)
			(end -0.32512 -0.175006)
			(stroke
				(width 0.1)
				(type default)
			)
			(layer "F.Fab")
		)
		(fp_line
			(start -0.32512 -0.175006)
			(end 0.32512 -0.175006)
			(stroke
				(width 0.1)
				(type default)
			)
			(layer "F.Fab")
		)
		(pad "1" smd rect
			(at -0.2667 0 180)
			(size 0.3048 0.381)
			(layers "F.Cu" "F.Mask" "F.Paste")
			(net "P1V8_CPU1_RT_1D")
		)
		(pad "2" smd rect
			(at 0.2667 0)
			(size 0.3048 0.381)
			(layers "F.Cu" "F.Mask" "F.Paste")
			(net "JTAG_TDO_RT_CPU1_P1")
		)
	)
	(footprint ""
		(layer "F.Cu")
		(at 149.230334 -191.371982 -90)
		(property "Reference" "R3197"
			(at 0 0 270)
			(layer "F.SilkS")
			(hide yes)
			(effects
				(font
					(size 1.27 1.27)
				)
			)
		)
		(property "Value" ""
			(at 0 0 270)
			(layer "F.Fab")
			(effects
				(font
					(size 1.27 1.27)
				)
			)
		)
		(duplicate_pad_numbers_are_jumpers no)
		(fp_line
			(start -0.7874 0.4064)
			(end -0.7874 0.056134)
			(stroke
				(width 0.1524)
				(type default)
			)
			(layer "F.SilkS")
		)
		(fp_line
			(start 0.7874 0.4064)
			(end -0.7874 0.4064)
			(stroke
				(width 0.1524)
				(type default)
			)
			(layer "F.SilkS")
		)
		(fp_line
			(start 0.7874 -0.045466)
			(end 0.7874 0.4064)
			(stroke
				(width 0.1524)
				(type default)
			)
			(layer "F.SilkS")
		)
		(fp_line
			(start -0.347218 -0.4064)
			(end 0.440182 -0.4064)
			(stroke
				(width 0.1524)
				(type default)
			)
			(layer "F.SilkS")
		)
		(fp_line
			(start -0.67945 0.3048)
			(end -0.67945 -0.305054)
			(stroke
				(width 0.1)
				(type default)
			)
			(layer "F.Fab")
		)
		(fp_line
			(start -0.12065 0.3048)
			(end -0.67945 0.3048)
			(stroke
				(width 0.1)
				(type default)
			)
			(layer "F.Fab")
		)
		(fp_line
			(start 0.120396 0.3048)
			(end 0.120396 0.2794)
			(stroke
				(width 0.1)
				(type default)
			)
			(layer "F.Fab")
		)
		(fp_line
			(start 0.67945 0.3048)
			(end 0.120396 0.3048)
			(stroke
				(width 0.1)
				(type default)
			)
			(layer "F.Fab")
		)
		(fp_line
			(start -0.12065 0.2794)
			(end -0.12065 0.3048)
			(stroke
				(width 0.1)
				(type default)
			)
			(layer "F.Fab")
		)
		(fp_line
			(start 0.120396 0.2794)
			(end -0.12065 0.2794)
			(stroke
				(width 0.1)
				(type default)
			)
			(layer "F.Fab")
		)
		(fp_line
			(start -0.12065 -0.2794)
			(end 0.12065 -0.2794)
			(stroke
				(width 0.1)
				(type default)
			)
			(layer "F.Fab")
		)
		(fp_line
			(start 0.12065 -0.2794)
			(end 0.12065 -0.3048)
			(stroke
				(width 0.1)
				(type default)
			)
			(layer "F.Fab")
		)
		(fp_line
			(start 0.12065 -0.3048)
			(end 0.67945 -0.3048)
			(stroke
				(width 0.1)
				(type default)
			)
			(layer "F.Fab")
		)
		(fp_line
			(start 0.67945 -0.3048)
			(end 0.67945 0.3048)
			(stroke
				(width 0.1)
				(type default)
			)
			(layer "F.Fab")
		)
		(fp_line
			(start -0.67945 -0.305054)
			(end -0.12065 -0.305054)
			(stroke
				(width 0.1)
				(type default)
			)
			(layer "F.Fab")
		)
		(fp_line
			(start -0.12065 -0.305054)
			(end -0.12065 -0.2794)
			(stroke
				(width 0.1)
				(type default)
			)
			(layer "F.Fab")
		)
		(pad "1" smd circle
			(at -0.40005 0 270)
			(size 0 0)
			(layers "F.Cu" "F.Mask" "F.Paste")
			(net "CLK_100M_CPU1_CLK03_R_DN")
		)
		(pad "2" smd circle
			(at 0.40005 0 270)
			(size 0 0)
			(layers "F.Cu" "F.Mask" "F.Paste")
			(net "CLK_100M_CPU1_CLK03_DN")
		)
	)
)
